(kicad_pcb
	(version 20260206)
	(generator "pcbnew")
	(generator_version "10.0")
	(general
		(thickness 1.6)
		(legacy_teardrops no)
	)
	(paper "A4")
	(title_block
		(title "9052_F0T_PDB_Converter_Brick_F_V03_1208_1600_OCP.brd")
		(comment 1 "Grand Teton / footprints 45-52 of 578")
	)
	(layers
		(0 "F.Cu" signal "TOP")
		(4 "In1.Cu" signal "GND")
		(6 "In2.Cu" signal "IN1")
		(8 "In3.Cu" signal "GND1")
		(10 "In4.Cu" signal "VCC")
		(12 "In5.Cu" signal "VCC1")
		(14 "In6.Cu" signal "GND2")
		(16 "In7.Cu" signal "IN2")
		(18 "In8.Cu" signal "GND3")
		(2 "B.Cu" signal "BOTTOM")
		(9 "F.Adhes" user "F.Adhesive")
		(11 "B.Adhes" user "B.Adhesive")
		(13 "F.Paste" user "Package Geometry/Pastemask Top")
		(15 "B.Paste" user "Package Geometry/Pastemask Bottom")
		(5 "F.SilkS" user "Ref Des/Silkscreen Top")
		(7 "B.SilkS" user "Ref Des/Silkscreen Bottom")
		(1 "F.Mask" user "Board Geometry/Soldermask Top")
		(3 "B.Mask" user "Board Geometry/Soldermask Bottom")
		(17 "Dwgs.User" user "User.Drawings")
		(19 "Cmts.User" user "User.Comments")
		(21 "Eco1.User" user "User.Eco1")
		(23 "Eco2.User" user "User.Eco2")
		(25 "Edge.Cuts" user "Board Geometry/Outline")
		(27 "Margin" user)
		(31 "F.CrtYd" user "Package Geometry/Place Bound Top")
		(29 "B.CrtYd" user "Package Geometry/Place Bound Bottom")
		(35 "F.Fab" user "Ref Des/Assembly Top")
		(33 "B.Fab" user "Ref Des/Assembly Bottom")
	)
	(footprint ""
		(layer "F.Cu")
		(at 44.45 -25.527)
		(property "Reference" "H21"
			(at -1.016 -3.40233 0)
			(unlocked yes)
			(layer "F.SilkS")
			(effects
				(font
					(size 0.7874 0.5842)
					(thickness 0.1524)
				)
				(justify left)
			)
		)
		(property "Value" ""
			(at 0 0 0)
			(layer "F.Fab")
			(effects
				(font
					(size 1.27 1.27)
				)
			)
		)
		(duplicate_pad_numbers_are_jumpers no)
		(fp_circle
			(center 0 0)
			(end 2.4003 0)
			(stroke
				(width 0.1524)
				(type default)
			)
			(fill no)
			(layer "F.SilkS")
		)
		(fp_circle
			(center 0 0)
			(end 6.5913 0)
			(stroke
				(width 0.1524)
				(type default)
			)
			(fill no)
			(layer "B.SilkS")
		)
		(fp_circle
			(center 0 0)
			(end 6.5913 0)
			(stroke
				(width 0.1)
				(type default)
			)
			(fill no)
			(layer "B.Fab")
		)
		(fp_circle
			(center 0 0)
			(end 2.4003 0)
			(stroke
				(width 0.1)
				(type default)
			)
			(fill no)
			(layer "F.Fab")
		)
		(pad "" np_thru_hole circle
			(at 0 0)
			(size 3.175 3.175)
			(drill 3.175)
			(layers "*.Cu" "*.Mask")
			(clearance 0.381)
			(thermal_gap 0.381)
		)
		(zone
			(layers "F.Cu" "B.Cu" "In1.Cu" "In2.Cu" "In3.Cu" "In4.Cu" "In5.Cu" "In6.Cu"
				"In7.Cu" "In8.Cu"
			)
			(hatch none 0.5)
			(connect_pads
				(clearance 0)
			)
			(min_thickness 0.25)
			(keepout
				(tracks not_allowed)
				(vias allowed)
				(pads allowed)
				(copperpour not_allowed)
				(footprints allowed)
			)
			(placement
				(enabled no)
				(sheetname "")
			)
			(fill
				(thermal_gap 0.5)
				(thermal_bridge_width 0.5)
				(island_removal_mode 0)
			)
			(polygon
				(pts
					(arc
						(start 46.5455 -25.527)
						(mid 42.3545 -25.527)
						(end 46.5455 -25.527)
					)
				)
			)
		)
	)
	(footprint ""
		(layer "F.Cu")
		(at 278.13 -50.673)
		(property "Reference" "PR19"
			(at 0 0 0)
			(layer "F.SilkS")
			(hide yes)
			(effects
				(font
					(size 1.27 1.27)
				)
			)
		)
		(property "Value" ""
			(at 0 0 0)
			(layer "F.Fab")
			(effects
				(font
					(size 1.27 1.27)
				)
			)
		)
		(duplicate_pad_numbers_are_jumpers no)
		(fp_line
			(start -1.651 -0.8382)
			(end 1.651 -0.8382)
			(stroke
				(width 0.1524)
				(type default)
			)
			(layer "F.SilkS")
		)
		(fp_line
			(start -1.651 0.8382)
			(end -1.651 -0.8382)
			(stroke
				(width 0.1524)
				(type default)
			)
			(layer "F.SilkS")
		)
		(fp_line
			(start 1.651 -0.8382)
			(end 1.651 0.8382)
			(stroke
				(width 0.1524)
				(type default)
			)
			(layer "F.SilkS")
		)
		(fp_line
			(start 1.651 0.8382)
			(end -1.651 0.8382)
			(stroke
				(width 0.1524)
				(type default)
			)
			(layer "F.SilkS")
		)
		(fp_line
			(start -1.559814 -0.7366)
			(end -1.559814 0.7366)
			(stroke
				(width 0.1)
				(type default)
			)
			(layer "F.Fab")
		)
		(fp_line
			(start -1.559814 0.7366)
			(end -1.524 0.7366)
			(stroke
				(width 0.1)
				(type default)
			)
			(layer "F.Fab")
		)
		(fp_line
			(start -1.524 -0.7366)
			(end -1.559814 -0.7366)
			(stroke
				(width 0.1)
				(type default)
			)
			(layer "F.Fab")
		)
		(fp_line
			(start -1.524 0.7366)
			(end 1.524 0.7366)
			(stroke
				(width 0.1)
				(type default)
			)
			(layer "F.Fab")
		)
		(fp_line
			(start 1.524 -0.7366)
			(end -1.524 -0.7366)
			(stroke
				(width 0.1)
				(type default)
			)
			(layer "F.Fab")
		)
		(fp_line
			(start 1.524 0.7366)
			(end 1.560576 0.7366)
			(stroke
				(width 0.1)
				(type default)
			)
			(layer "F.Fab")
		)
		(fp_line
			(start 1.560576 -0.7366)
			(end 1.524 -0.7366)
			(stroke
				(width 0.1)
				(type default)
			)
			(layer "F.Fab")
		)
		(fp_line
			(start 1.560576 0.7366)
			(end 1.560576 -0.7366)
			(stroke
				(width 0.1)
				(type default)
			)
			(layer "F.Fab")
		)
		(pad "1" smd rect
			(at -0.94996 0 180)
			(size 1.1176 1.3716)
			(layers "F.Cu" "F.Mask" "F.Paste")
			(net "P52V_HS")
		)
		(pad "2" smd rect
			(at 0.94996 0 180)
			(size 1.1176 1.3716)
			(layers "F.Cu" "F.Mask" "F.Paste")
			(net "P52V_HS1_ISET")
		)
	)
	(footprint ""
		(layer "F.Cu")
		(at 205.613 -67.056 -90)
		(property "Reference" "D3"
			(at 3.048 -0.02667 90)
			(unlocked yes)
			(layer "F.SilkS")
			(effects
				(font
					(size 0.7874 0.5842)
					(thickness 0.1524)
				)
				(justify left)
			)
		)
		(property "Value" ""
			(at 0 0 270)
			(layer "F.Fab")
			(effects
				(font
					(size 1.27 1.27)
				)
			)
		)
		(duplicate_pad_numbers_are_jumpers no)
		(fp_line
			(start -0.90678 0.4826)
			(end -0.90678 -0.4699)
			(stroke
				(width 0.1524)
				(type default)
			)
			(layer "F.SilkS")
		)
		(fp_line
			(start 0.90678 0.4826)
			(end -0.90678 0.4826)
			(stroke
				(width 0.1524)
				(type default)
			)
			(layer "F.SilkS")
		)
		(fp_line
			(start 1.03378 0.4826)
			(end -0.79248 0.4826)
			(stroke
				(width 0.1524)
				(type default)
			)
			(layer "F.SilkS")
		)
		(fp_line
			(start 1.16078 0.4826)
			(end -0.64008 0.4826)
			(stroke
				(width 0.1524)
				(type default)
			)
			(layer "F.SilkS")
		)
		(fp_line
			(start -0.89408 -0.4826)
			(end 0.90678 -0.4826)
			(stroke
				(width 0.1524)
				(type default)
			)
			(layer "F.SilkS")
		)
		(fp_line
			(start -0.79248 -0.4826)
			(end 1.03378 -0.4826)
			(stroke
				(width 0.1524)
				(type default)
			)
			(layer "F.SilkS")
		)
		(fp_line
			(start -0.64008 -0.4826)
			(end 1.16078 -0.4826)
			(stroke
				(width 0.1524)
				(type default)
			)
			(layer "F.SilkS")
		)
		(fp_line
			(start 0.90678 -0.4826)
			(end 0.90678 0.4826)
			(stroke
				(width 0.1524)
				(type default)
			)
			(layer "F.SilkS")
		)
		(fp_line
			(start 1.03378 -0.4826)
			(end 1.03378 0.4826)
			(stroke
				(width 0.1524)
				(type default)
			)
			(layer "F.SilkS")
		)
		(fp_line
			(start 1.16078 -0.4826)
			(end 1.16078 0.4826)
			(stroke
				(width 0.1524)
				(type default)
			)
			(layer "F.SilkS")
		)
		(fp_line
			(start -0.499872 0.249936)
			(end -0.499872 -0.249936)
			(stroke
				(width 0.1)
				(type default)
			)
			(layer "F.Fab")
		)
		(fp_line
			(start 0.499872 0.249936)
			(end -0.499872 0.249936)
			(stroke
				(width 0.1)
				(type default)
			)
			(layer "F.Fab")
		)
		(fp_line
			(start -0.499872 -0.249936)
			(end 0.499872 -0.249936)
			(stroke
				(width 0.1)
				(type default)
			)
			(layer "F.Fab")
		)
		(fp_line
			(start 0.499872 -0.249936)
			(end 0.499872 0.249936)
			(stroke
				(width 0.1)
				(type default)
			)
			(layer "F.Fab")
		)
		(pad "A" smd rect
			(at -0.47498 0 270)
			(size 0.6096 0.7112)
			(layers "F.Cu" "F.Mask" "F.Paste")
			(net "LED_D3_R")
		)
		(pad "C" smd rect
			(at 0.47498 0 270)
			(size 0.6096 0.7112)
			(layers "F.Cu" "F.Mask" "F.Paste")
			(net "GND")
		)
	)
	(footprint ""
		(layer "F.Cu")
		(at 108.839 -60.96)
		(property "Reference" "PC68"
			(at -1.524 -3.52933 0)
			(unlocked yes)
			(layer "F.SilkS")
			(effects
				(font
					(size 0.7874 0.5842)
					(thickness 0.1524)
				)
				(justify left)
			)
		)
		(property "Value" ""
			(at 0 0 0)
			(layer "F.Fab")
			(effects
				(font
					(size 1.27 1.27)
				)
			)
		)
		(duplicate_pad_numbers_are_jumpers no)
		(fp_line
			(start 5.2578 2.499868)
			(end -5.2578 2.499868)
			(stroke
				(width 0.1524)
				(type default)
			)
			(layer "F.SilkS")
		)
		(fp_circle
			(center 0 2.499868)
			(end 5.2578 2.499868)
			(stroke
				(width 0.1524)
				(type default)
			)
			(fill no)
			(layer "F.SilkS")
		)
		(fp_poly
			(pts
				(arc
					(start 5.2578 2.499868)
					(mid 0 7.757922)
					(end -5.2578 2.499868)
				)
			)
			(stroke
				(width 0)
				(type default)
			)
			(fill yes)
			(layer "F.SilkS")
		)
		(fp_circle
			(center 0 2.499868)
			(end 5.2578 2.499868)
			(stroke
				(width 0.1)
				(type default)
			)
			(fill no)
			(layer "F.Fab")
		)
		(pad "1" thru_hole rect
			(at 0 0 270)
			(size 1.524 1.524)
			(drill 1.016)
			(layers "*.Cu" "*.Mask")
			(remove_unused_layers no)
			(net "P12V_BRICK")
			(clearance 0)
			(padstack
				(mode front_inner_back)
				(layer "Inner"
					(shape circle)
					(size 1.524 1.524)
					(clearance 0)
				)
				(layer "B.Cu"
					(shape rect)
					(size 1.524 1.524)
					(clearance 0)
				)
			)
		)
		(pad "2" thru_hole circle
			(at 0 4.99999 270)
			(size 1.524 1.524)
			(drill 1.016)
			(layers "*.Cu" "*.Mask")
			(remove_unused_layers no)
			(net "GND")
			(clearance 0)
		)
	)
	(footprint ""
		(layer "F.Cu")
		(at 264.808716 -35.373818 180)
		(property "Reference" "PC7"
			(at 0 0 180)
			(layer "F.SilkS")
			(hide yes)
			(effects
				(font
					(size 1.27 1.27)
				)
			)
		)
		(property "Value" ""
			(at 0 0 180)
			(layer "F.Fab")
			(effects
				(font
					(size 1.27 1.27)
				)
			)
		)
		(duplicate_pad_numbers_are_jumpers no)
		(fp_line
			(start 0.7874 0.4064)
			(end -0.7874 0.4064)
			(stroke
				(width 0.1524)
				(type default)
			)
			(layer "F.SilkS")
		)
		(fp_line
			(start 0.7874 -0.4064)
			(end 0.7874 0.4064)
			(stroke
				(width 0.1524)
				(type default)
			)
			(layer "F.SilkS")
		)
		(fp_line
			(start -0.7874 0.4064)
			(end -0.7874 -0.4064)
			(stroke
				(width 0.1524)
				(type default)
			)
			(layer "F.SilkS")
		)
		(fp_line
			(start -0.7874 -0.4064)
			(end 0.7874 -0.4064)
			(stroke
				(width 0.1524)
				(type default)
			)
			(layer "F.SilkS")
		)
		(fp_line
			(start 0.67945 0.3048)
			(end 0.120396 0.3048)
			(stroke
				(width 0.1)
				(type default)
			)
			(layer "F.Fab")
		)
		(fp_line
			(start 0.67945 -0.3048)
			(end 0.67945 0.3048)
			(stroke
				(width 0.1)
				(type default)
			)
			(layer "F.Fab")
		)
		(fp_line
			(start 0.12065 -0.2794)
			(end 0.12065 -0.3048)
			(stroke
				(width 0.1)
				(type default)
			)
			(layer "F.Fab")
		)
		(fp_line
			(start 0.12065 -0.3048)
			(end 0.67945 -0.3048)
			(stroke
				(width 0.1)
				(type default)
			)
			(layer "F.Fab")
		)
		(fp_line
			(start 0.120396 0.3048)
			(end 0.120396 0.2794)
			(stroke
				(width 0.1)
				(type default)
			)
			(layer "F.Fab")
		)
		(fp_line
			(start 0.120396 0.2794)
			(end -0.12065 0.2794)
			(stroke
				(width 0.1)
				(type default)
			)
			(layer "F.Fab")
		)
		(fp_line
			(start -0.12065 0.3048)
			(end -0.67945 0.3048)
			(stroke
				(width 0.1)
				(type default)
			)
			(layer "F.Fab")
		)
		(fp_line
			(start -0.12065 0.2794)
			(end -0.12065 0.3048)
			(stroke
				(width 0.1)
				(type default)
			)
			(layer "F.Fab")
		)
		(fp_line
			(start -0.12065 -0.2794)
			(end 0.12065 -0.2794)
			(stroke
				(width 0.1)
				(type default)
			)
			(layer "F.Fab")
		)
		(fp_line
			(start -0.12065 -0.305054)
			(end -0.12065 -0.2794)
			(stroke
				(width 0.1)
				(type default)
			)
			(layer "F.Fab")
		)
		(fp_line
			(start -0.67945 0.3048)
			(end -0.67945 -0.305054)
			(stroke
				(width 0.1)
				(type default)
			)
			(layer "F.Fab")
		)
		(fp_line
			(start -0.67945 -0.305054)
			(end -0.12065 -0.305054)
			(stroke
				(width 0.1)
				(type default)
			)
			(layer "F.Fab")
		)
		(pad "1" smd circle
			(at -0.40005 0 180)
			(size 0 0)
			(layers "F.Cu" "F.Mask" "F.Paste")
			(net "P52V_HS1_TMR")
		)
		(pad "2" smd circle
			(at 0.40005 0 180)
			(size 0 0)
			(layers "F.Cu" "F.Mask" "F.Paste")
			(net "GND_FIELD_SIGNAL")
		)
	)
	(footprint ""
		(layer "F.Cu")
		(at 297.538394 -86.8045 180)
		(property "Reference" "PR6954"
			(at 0 0 180)
			(layer "F.SilkS")
			(hide yes)
			(effects
				(font
					(size 1.27 1.27)
				)
			)
		)
		(property "Value" ""
			(at 0 0 180)
			(layer "F.Fab")
			(effects
				(font
					(size 1.27 1.27)
				)
			)
		)
		(duplicate_pad_numbers_are_jumpers no)
		(fp_line
			(start 1.2954 0.5842)
			(end -1.2954 0.5842)
			(stroke
				(width 0.1524)
				(type default)
			)
			(layer "F.SilkS")
		)
		(fp_line
			(start 1.2954 -0.5842)
			(end 1.2954 0.5842)
			(stroke
				(width 0.1524)
				(type default)
			)
			(layer "F.SilkS")
		)
		(fp_line
			(start -1.2954 0.5842)
			(end -1.2954 -0.5842)
			(stroke
				(width 0.1524)
				(type default)
			)
			(layer "F.SilkS")
		)
		(fp_line
			(start -1.2954 -0.5842)
			(end 1.2954 -0.5842)
			(stroke
				(width 0.1524)
				(type default)
			)
			(layer "F.SilkS")
		)
		(fp_line
			(start 1.1938 0.4064)
			(end 0.8636 0.4064)
			(stroke
				(width 0.1)
				(type default)
			)
			(layer "F.Fab")
		)
		(fp_line
			(start 1.1938 -0.406654)
			(end 1.1938 0.4064)
			(stroke
				(width 0.1)
				(type default)
			)
			(layer "F.Fab")
		)
		(fp_line
			(start 0.8636 0.4572)
			(end -0.8636 0.4572)
			(stroke
				(width 0.1)
				(type default)
			)
			(layer "F.Fab")
		)
		(fp_line
			(start 0.8636 0.4064)
			(end 0.8636 0.4572)
			(stroke
				(width 0.1)
				(type default)
			)
			(layer "F.Fab")
		)
		(fp_line
			(start 0.8636 -0.406654)
			(end 1.1938 -0.406654)
			(stroke
				(width 0.1)
				(type default)
			)
			(layer "F.Fab")
		)
		(fp_line
			(start 0.8636 -0.4572)
			(end 0.8636 -0.406654)
			(stroke
				(width 0.1)
				(type default)
			)
			(layer "F.Fab")
		)
		(fp_line
			(start -0.8636 0.4572)
			(end -0.8636 0.4318)
			(stroke
				(width 0.1)
				(type default)
			)
			(layer "F.Fab")
		)
		(fp_line
			(start -0.8636 0.4318)
			(end -0.8636 0.4064)
			(stroke
				(width 0.1)
				(type default)
			)
			(layer "F.Fab")
		)
		(fp_line
			(start -0.8636 0.4064)
			(end -1.1938 0.4064)
			(stroke
				(width 0.1)
				(type default)
			)
			(layer "F.Fab")
		)
		(fp_line
			(start -0.8636 -0.406654)
			(end -0.8636 -0.4572)
			(stroke
				(width 0.1)
				(type default)
			)
			(layer "F.Fab")
		)
		(fp_line
			(start -0.8636 -0.4572)
			(end 0.8636 -0.4572)
			(stroke
				(width 0.1)
				(type default)
			)
			(layer "F.Fab")
		)
		(fp_line
			(start -1.1938 0.4064)
			(end -1.1938 -0.406654)
			(stroke
				(width 0.1)
				(type default)
			)
			(layer "F.Fab")
		)
		(fp_line
			(start -1.1938 -0.406654)
			(end -0.8636 -0.406654)
			(stroke
				(width 0.1)
				(type default)
			)
			(layer "F.Fab")
		)
		(pad "1" smd rect
			(at -0.7366 0 90)
			(size 0.7112 0.8128)
			(layers "F.Cu" "F.Mask" "F.Paste")
			(net "P52V_HS_4287_S2N")
		)
		(pad "2" smd rect
			(at 0.7366 0 90)
			(size 0.7112 0.8128)
			(layers "F.Cu" "F.Mask" "F.Paste")
			(net "P52V_HS1_SENSE_N_R2")
		)
	)
	(footprint ""
		(layer "F.Cu")
		(at 226.59594 -20.604988)
		(property "Reference" ""
			(at 0 0 0)
			(layer "F.SilkS")
			(hide yes)
			(effects
				(font
					(size 1.27 1.27)
				)
			)
		)
		(property "Value" ""
			(at 0 0 0)
			(layer "F.Fab")
			(effects
				(font
					(size 1.27 1.27)
				)
			)
		)
		(duplicate_pad_numbers_are_jumpers no)
		(pad "1" smd circle
			(at 0 0)
			(size 0.9906 0.9906)
			(layers "F.Cu" "F.Mask" "F.Paste")
			(net "Net_155")
		)
		(zone
			(layer "F.Cu")
			(hatch none 0.5)
			(connect_pads
				(clearance 0)
			)
			(min_thickness 0.25)
			(keepout
				(tracks not_allowed)
				(vias allowed)
				(pads allowed)
				(copperpour not_allowed)
				(footprints allowed)
			)
			(placement
				(enabled no)
				(sheetname "")
			)
			(fill
				(thermal_gap 0.5)
				(thermal_bridge_width 0.5)
				(island_removal_mode 0)
			)
			(polygon
				(pts
					(arc
						(start 228.22154 -20.604988)
						(mid 224.97034 -20.604988)
						(end 228.22154 -20.604988)
					)
				)
			)
		)
	)
	(footprint ""
		(layer "F.Cu")
		(at 174.0662 -12.4968 90)
		(property "Reference" "PC100"
			(at 0 0 90)
			(layer "F.SilkS")
			(hide yes)
			(effects
				(font
					(size 1.27 1.27)
				)
			)
		)
		(property "Value" ""
			(at 0 0 90)
			(layer "F.Fab")
			(effects
				(font
					(size 1.27 1.27)
				)
			)
		)
		(duplicate_pad_numbers_are_jumpers no)
		(fp_line
			(start 1.524 -0.762)
			(end 1.524 0.762)
			(stroke
				(width 0.1524)
				(type default)
			)
			(layer "F.SilkS")
		)
		(fp_line
			(start -1.524 -0.762)
			(end 1.524 -0.762)
			(stroke
				(width 0.1524)
				(type default)
			)
			(layer "F.SilkS")
		)
		(fp_line
			(start 1.524 0.762)
			(end -1.524 0.762)
			(stroke
				(width 0.1524)
				(type default)
			)
			(layer "F.SilkS")
		)
		(fp_line
			(start -1.524 0.762)
			(end -1.524 -0.762)
			(stroke
				(width 0.1524)
				(type default)
			)
			(layer "F.SilkS")
		)
		(fp_line
			(start 1.1049 -0.724916)
			(end -1.1049 -0.724916)
			(stroke
				(width 0.1)
				(type default)
			)
			(layer "F.Fab")
		)
		(fp_line
			(start -1.1049 -0.724916)
			(end -1.1049 0.724916)
			(stroke
				(width 0.1)
				(type default)
			)
			(layer "F.Fab")
		)
		(fp_line
			(start 1.1049 0.724916)
			(end 1.1049 -0.724916)
			(stroke
				(width 0.1)
				(type default)
			)
			(layer "F.Fab")
		)
		(fp_line
			(start -1.1049 0.724916)
			(end 1.1049 0.724916)
			(stroke
				(width 0.1)
				(type default)
			)
			(layer "F.Fab")
		)
		(pad "1" smd rect
			(at -0.889 0 270)
			(size 1.016 1.27)
			(layers "F.Cu" "F.Mask" "F.Paste")
			(net "SW_P12V_FILT__P3V3_AUX")
		)
		(pad "2" smd rect
			(at 0.889 0 270)
			(size 1.016 1.27)
			(layers "F.Cu" "F.Mask" "F.Paste")
			(net "GND")
		)
	)
)
